(kicad_pcb
	(version 20260206)
	(generator "pcbnew")
	(generator_version "10.0")
	(general
		(thickness 1.6)
		(legacy_teardrops no)
	)
	(paper "A4")
	(title_block
		(title "Wiwynn_Tioga_Pass_MB.brd")
		(comment 1 "Tioga Pass / footprints 4191-4197 of 4770")
	)
	(layers
		(0 "F.Cu" signal "TOP")
		(4 "In1.Cu" signal "L2GND")
		(6 "In2.Cu" signal "L3")
		(8 "In3.Cu" signal "L4GND")
		(10 "In4.Cu" signal "L5")
		(12 "In5.Cu" signal "L6GND")
		(14 "In6.Cu" signal "L7VCC")
		(16 "In7.Cu" signal "L8VCC")
		(18 "In8.Cu" signal "L9GND")
		(20 "In9.Cu" signal "L10")
		(22 "In10.Cu" signal "L11GND")
		(24 "In11.Cu" signal "L12")
		(26 "In12.Cu" signal "L13GND")
		(2 "B.Cu" signal "BOTTOM")
		(9 "F.Adhes" user "F.Adhesive")
		(11 "B.Adhes" user "B.Adhesive")
		(13 "F.Paste" user "Package Geometry/Pastemask Top")
		(15 "B.Paste" user "Package Geometry/Pastemask Bottom")
		(5 "F.SilkS" user "Ref Des/Silkscreen Top")
		(7 "B.SilkS" user "Ref Des/Silkscreen Bottom")
		(1 "F.Mask" user "Board Geometry/Soldermask Top")
		(3 "B.Mask" user "Board Geometry/Soldermask Bottom")
		(17 "Dwgs.User" user "User.Drawings")
		(19 "Cmts.User" user "User.Comments")
		(21 "Eco1.User" user "User.Eco1")
		(23 "Eco2.User" user "User.Eco2")
		(25 "Edge.Cuts" user "Board Geometry/Outline")
		(27 "Margin" user)
		(31 "F.CrtYd" user "Package Geometry/Place Bound Top")
		(29 "B.CrtYd" user "Package Geometry/Place Bound Bottom")
		(35 "F.Fab" user "Ref Des/Assembly Top")
		(33 "B.Fab" user "Ref Des/Assembly Bottom")
	)
	(footprint ""
		(layer "B.Cu")
		(at 404.5585 -97.155 -90)
		(property "Reference" "R2N16"
			(at 0 0 90)
			(layer "B.SilkS")
			(hide yes)
			(effects
				(font
					(size 1.27 1.27)
				)
				(justify mirror)
			)
		)
		(property "Value" ""
			(at 0 0 90)
			(layer "B.Fab")
			(effects
				(font
					(size 1.27 1.27)
				)
				(justify mirror)
			)
		)
		(duplicate_pad_numbers_are_jumpers no)
		(fp_poly
			(pts
				(xy 0.2794 -0.1016) (xy -0.2794 -0.1016) (xy -0.2794 0.9906) (xy 0.2794 0.9906)
			)
			(stroke
				(width 0)
				(type default)
			)
			(fill no)
			(layer "B.CrtYd")
		)
		(fp_line
			(start -0.2794 0.9906)
			(end -0.2794 -0.1016)
			(stroke
				(width 0.1)
				(type default)
			)
			(layer "B.Fab")
		)
		(fp_line
			(start 0.2794 0.9906)
			(end -0.2794 0.9906)
			(stroke
				(width 0.1)
				(type default)
			)
			(layer "B.Fab")
		)
		(fp_line
			(start -0.2794 -0.1016)
			(end 0.2794 -0.1016)
			(stroke
				(width 0.1)
				(type default)
			)
			(layer "B.Fab")
		)
		(fp_line
			(start 0.2794 -0.1016)
			(end 0.2794 0.9906)
			(stroke
				(width 0.1)
				(type default)
			)
			(layer "B.Fab")
		)
		(pad "1" smd rect
			(at 0 0 90)
			(size 0.508 0.508)
			(layers "B.Cu" "B.Mask" "B.Paste")
			(net "P3V3_STBY")
		)
		(pad "2" smd rect
			(at 0 0.889 90)
			(size 0.508 0.508)
			(layers "B.Cu" "B.Mask" "B.Paste")
			(net "PU_IRQ_VRALERT_N")
		)
		(zone
			(layer "B.Cu")
			(hatch none 0.5)
			(connect_pads
				(clearance 0)
			)
			(min_thickness 0.25)
			(keepout
				(tracks not_allowed)
				(vias allowed)
				(pads allowed)
				(copperpour not_allowed)
				(footprints allowed)
			)
			(placement
				(enabled no)
				(sheetname "")
			)
			(fill
				(thermal_gap 0.5)
				(thermal_bridge_width 0.5)
				(island_removal_mode 0)
			)
			(polygon
				(pts
					(xy 403.9235 -96.901) (xy 403.9235 -97.409) (xy 404.3045 -97.409) (xy 404.3045 -96.901)
				)
			)
		)
		(zone
			(layer "B.Cu")
			(hatch none 0.5)
			(connect_pads
				(clearance 0)
			)
			(min_thickness 0.25)
			(keepout
				(tracks allowed)
				(vias not_allowed)
				(pads allowed)
				(copperpour not_allowed)
				(footprints allowed)
			)
			(placement
				(enabled no)
				(sheetname "")
			)
			(fill
				(thermal_gap 0.5)
				(thermal_bridge_width 0.5)
				(island_removal_mode 0)
			)
			(polygon
				(pts
					(xy 404.3045 -96.901) (xy 404.3045 -97.409) (xy 403.9235 -97.409) (xy 403.9235 -96.901)
				)
			)
		)
	)
	(footprint ""
		(layer "B.Cu")
		(at 27.912568 -134.874 180)
		(property "Reference" "R9M2"
			(at 0 0 0)
			(layer "B.SilkS")
			(hide yes)
			(effects
				(font
					(size 1.27 1.27)
				)
				(justify mirror)
			)
		)
		(property "Value" ""
			(at 0 0 0)
			(layer "B.Fab")
			(effects
				(font
					(size 1.27 1.27)
				)
				(justify mirror)
			)
		)
		(duplicate_pad_numbers_are_jumpers no)
		(fp_poly
			(pts
				(xy 0.2794 -0.1016) (xy -0.2794 -0.1016) (xy -0.2794 0.9906) (xy 0.2794 0.9906)
			)
			(stroke
				(width 0)
				(type default)
			)
			(fill no)
			(layer "B.CrtYd")
		)
		(fp_line
			(start 0.2794 0.9906)
			(end -0.2794 0.9906)
			(stroke
				(width 0.1)
				(type default)
			)
			(layer "B.Fab")
		)
		(fp_line
			(start 0.2794 -0.1016)
			(end 0.2794 0.9906)
			(stroke
				(width 0.1)
				(type default)
			)
			(layer "B.Fab")
		)
		(fp_line
			(start -0.2794 0.9906)
			(end -0.2794 -0.1016)
			(stroke
				(width 0.1)
				(type default)
			)
			(layer "B.Fab")
		)
		(fp_line
			(start -0.2794 -0.1016)
			(end 0.2794 -0.1016)
			(stroke
				(width 0.1)
				(type default)
			)
			(layer "B.Fab")
		)
		(pad "1" smd rect
			(at 0 0)
			(size 0.508 0.508)
			(layers "B.Cu" "B.Mask" "B.Paste")
			(net "M_K_CPU_VREF")
		)
		(pad "2" smd rect
			(at 0 0.889)
			(size 0.508 0.508)
			(layers "B.Cu" "B.Mask" "B.Paste")
			(net "M_K_VREF")
		)
		(zone
			(layer "B.Cu")
			(hatch none 0.5)
			(connect_pads
				(clearance 0)
			)
			(min_thickness 0.25)
			(keepout
				(tracks not_allowed)
				(vias allowed)
				(pads allowed)
				(copperpour not_allowed)
				(footprints allowed)
			)
			(placement
				(enabled no)
				(sheetname "")
			)
			(fill
				(thermal_gap 0.5)
				(thermal_bridge_width 0.5)
				(island_removal_mode 0)
			)
			(polygon
				(pts
					(xy 27.658568 -135.509) (xy 28.166568 -135.509) (xy 28.166568 -135.128) (xy 27.658568 -135.128)
				)
			)
		)
		(zone
			(layer "B.Cu")
			(hatch none 0.5)
			(connect_pads
				(clearance 0)
			)
			(min_thickness 0.25)
			(keepout
				(tracks allowed)
				(vias not_allowed)
				(pads allowed)
				(copperpour not_allowed)
				(footprints allowed)
			)
			(placement
				(enabled no)
				(sheetname "")
			)
			(fill
				(thermal_gap 0.5)
				(thermal_bridge_width 0.5)
				(island_removal_mode 0)
			)
			(polygon
				(pts
					(xy 27.658568 -135.128) (xy 28.166568 -135.128) (xy 28.166568 -135.509) (xy 27.658568 -135.509)
				)
			)
		)
	)
	(footprint ""
		(layer "B.Cu")
		(at 343.063068 -77.694536)
		(property "Reference" "C3P16"
			(at 0 0 0)
			(layer "B.SilkS")
			(hide yes)
			(effects
				(font
					(size 1.27 1.27)
				)
				(justify mirror)
			)
		)
		(property "Value" ""
			(at 0 0 0)
			(layer "B.Fab")
			(effects
				(font
					(size 1.27 1.27)
				)
				(justify mirror)
			)
		)
		(duplicate_pad_numbers_are_jumpers no)
		(fp_poly
			(pts
				(xy -0.3048 -0.1016) (xy -0.3048 0.9906) (xy 0.3048 0.9906) (xy 0.3048 -0.1016)
			)
			(stroke
				(width 0)
				(type default)
			)
			(fill no)
			(layer "B.CrtYd")
		)
		(fp_line
			(start -0.3048 -0.1016)
			(end 0.3048 -0.1016)
			(stroke
				(width 0.1)
				(type default)
			)
			(layer "B.Fab")
		)
		(fp_line
			(start -0.3048 0.9906)
			(end -0.3048 -0.1016)
			(stroke
				(width 0.1)
				(type default)
			)
			(layer "B.Fab")
		)
		(fp_line
			(start 0.3048 -0.1016)
			(end 0.3048 0.9906)
			(stroke
				(width 0.1)
				(type default)
			)
			(layer "B.Fab")
		)
		(fp_line
			(start 0.3048 0.9906)
			(end -0.3048 0.9906)
			(stroke
				(width 0.1)
				(type default)
			)
			(layer "B.Fab")
		)
		(pad "1" smd rect
			(at 0 0 180)
			(size 0.508 0.508)
			(layers "B.Cu" "B.Mask" "B.Paste")
			(net "P3E_CPU0_PE1_SS_TXN<1>")
		)
		(pad "2" smd rect
			(at 0 0.889 180)
			(size 0.508 0.508)
			(layers "B.Cu" "B.Mask" "B.Paste")
			(net "P3E_CPU0_PE1_SS_C_TXN<1>")
		)
		(zone
			(layer "B.Cu")
			(hatch none 0.5)
			(connect_pads
				(clearance 0)
			)
			(min_thickness 0.25)
			(keepout
				(tracks allowed)
				(vias not_allowed)
				(pads allowed)
				(copperpour not_allowed)
				(footprints allowed)
			)
			(placement
				(enabled no)
				(sheetname "")
			)
			(fill
				(thermal_gap 0.5)
				(thermal_bridge_width 0.5)
				(island_removal_mode 0)
			)
			(polygon
				(pts
					(xy 343.317068 -77.440536) (xy 342.809068 -77.440536) (xy 342.809068 -77.059536) (xy 343.317068 -77.059536)
				)
			)
		)
		(zone
			(layer "B.Cu")
			(hatch none 0.5)
			(connect_pads
				(clearance 0)
			)
			(min_thickness 0.25)
			(keepout
				(tracks not_allowed)
				(vias allowed)
				(pads allowed)
				(copperpour not_allowed)
				(footprints allowed)
			)
			(placement
				(enabled no)
				(sheetname "")
			)
			(fill
				(thermal_gap 0.5)
				(thermal_bridge_width 0.5)
				(island_removal_mode 0)
			)
			(polygon
				(pts
					(xy 343.317068 -77.059536) (xy 342.809068 -77.059536) (xy 342.809068 -77.440536) (xy 343.317068 -77.440536)
				)
			)
		)
	)
	(footprint ""
		(layer "B.Cu")
		(at 476.936816 -145.470372 180)
		(property "Reference" "R6W9"
			(at 0.8382 -0.67818 180)
			(unlocked yes)
			(layer "B.SilkS")
			(effects
				(font
					(size 0.4064 0.254)
					(thickness 0.1524)
				)
				(justify left mirror)
			)
		)
		(property "Value" ""
			(at 0 0 0)
			(layer "B.Fab")
			(effects
				(font
					(size 1.27 1.27)
				)
				(justify mirror)
			)
		)
		(duplicate_pad_numbers_are_jumpers no)
		(fp_poly
			(pts
				(xy 0.2794 -0.1016) (xy -0.2794 -0.1016) (xy -0.2794 0.9906) (xy 0.2794 0.9906)
			)
			(stroke
				(width 0)
				(type default)
			)
			(fill no)
			(layer "B.CrtYd")
		)
		(fp_line
			(start 0.2794 0.9906)
			(end -0.2794 0.9906)
			(stroke
				(width 0.1)
				(type default)
			)
			(layer "B.Fab")
		)
		(fp_line
			(start 0.2794 -0.1016)
			(end 0.2794 0.9906)
			(stroke
				(width 0.1)
				(type default)
			)
			(layer "B.Fab")
		)
		(fp_line
			(start -0.2794 0.9906)
			(end -0.2794 -0.1016)
			(stroke
				(width 0.1)
				(type default)
			)
			(layer "B.Fab")
		)
		(fp_line
			(start -0.2794 -0.1016)
			(end 0.2794 -0.1016)
			(stroke
				(width 0.1)
				(type default)
			)
			(layer "B.Fab")
		)
		(pad "1" smd rect
			(at 0 0)
			(size 0.508 0.508)
			(layers "B.Cu" "B.Mask" "B.Paste")
			(net "PCA9555_A0")
		)
		(pad "2" smd rect
			(at 0 0.889)
			(size 0.508 0.508)
			(layers "B.Cu" "B.Mask" "B.Paste")
			(net "GND")
		)
		(zone
			(layer "B.Cu")
			(hatch none 0.5)
			(connect_pads
				(clearance 0)
			)
			(min_thickness 0.25)
			(keepout
				(tracks not_allowed)
				(vias allowed)
				(pads allowed)
				(copperpour not_allowed)
				(footprints allowed)
			)
			(placement
				(enabled no)
				(sheetname "")
			)
			(fill
				(thermal_gap 0.5)
				(thermal_bridge_width 0.5)
				(island_removal_mode 0)
			)
			(polygon
				(pts
					(xy 476.682816 -146.105372) (xy 477.190816 -146.105372) (xy 477.190816 -145.724372) (xy 476.682816 -145.724372)
				)
			)
		)
		(zone
			(layer "B.Cu")
			(hatch none 0.5)
			(connect_pads
				(clearance 0)
			)
			(min_thickness 0.25)
			(keepout
				(tracks allowed)
				(vias not_allowed)
				(pads allowed)
				(copperpour not_allowed)
				(footprints allowed)
			)
			(placement
				(enabled no)
				(sheetname "")
			)
			(fill
				(thermal_gap 0.5)
				(thermal_bridge_width 0.5)
				(island_removal_mode 0)
			)
			(polygon
				(pts
					(xy 476.682816 -145.724372) (xy 477.190816 -145.724372) (xy 477.190816 -146.105372) (xy 476.682816 -146.105372)
				)
			)
		)
	)
	(footprint ""
		(layer "B.Cu")
		(at 369.443 -110.998 -90)
		(property "Reference" "C3N8"
			(at 0 0 90)
			(layer "B.SilkS")
			(hide yes)
			(effects
				(font
					(size 1.27 1.27)
				)
				(justify mirror)
			)
		)
		(property "Value" ""
			(at 0 0 90)
			(layer "B.Fab")
			(effects
				(font
					(size 1.27 1.27)
				)
				(justify mirror)
			)
		)
		(duplicate_pad_numbers_are_jumpers no)
		(fp_poly
			(pts
				(xy -0.3048 -0.1016) (xy -0.3048 0.9906) (xy 0.3048 0.9906) (xy 0.3048 -0.1016)
			)
			(stroke
				(width 0)
				(type default)
			)
			(fill no)
			(layer "B.CrtYd")
		)
		(fp_line
			(start -0.3048 0.9906)
			(end -0.3048 -0.1016)
			(stroke
				(width 0.1)
				(type default)
			)
			(layer "B.Fab")
		)
		(fp_line
			(start 0.3048 0.9906)
			(end -0.3048 0.9906)
			(stroke
				(width 0.1)
				(type default)
			)
			(layer "B.Fab")
		)
		(fp_line
			(start -0.3048 -0.1016)
			(end 0.3048 -0.1016)
			(stroke
				(width 0.1)
				(type default)
			)
			(layer "B.Fab")
		)
		(fp_line
			(start 0.3048 -0.1016)
			(end 0.3048 0.9906)
			(stroke
				(width 0.1)
				(type default)
			)
			(layer "B.Fab")
		)
		(pad "1" smd rect
			(at 0 0 90)
			(size 0.508 0.508)
			(layers "B.Cu" "B.Mask" "B.Paste")
			(net "DMI_CPU0_PCH_RX_DP<3>")
		)
		(pad "2" smd rect
			(at 0 0.889 90)
			(size 0.508 0.508)
			(layers "B.Cu" "B.Mask" "B.Paste")
			(net "DMI_CPU0_PCH_RX_C_DP<3>")
		)
		(zone
			(layer "B.Cu")
			(hatch none 0.5)
			(connect_pads
				(clearance 0)
			)
			(min_thickness 0.25)
			(keepout
				(tracks not_allowed)
				(vias allowed)
				(pads allowed)
				(copperpour not_allowed)
				(footprints allowed)
			)
			(placement
				(enabled no)
				(sheetname "")
			)
			(fill
				(thermal_gap 0.5)
				(thermal_bridge_width 0.5)
				(island_removal_mode 0)
			)
			(polygon
				(pts
					(xy 368.808 -110.744) (xy 368.808 -111.252) (xy 369.189 -111.252) (xy 369.189 -110.744)
				)
			)
		)
		(zone
			(layer "B.Cu")
			(hatch none 0.5)
			(connect_pads
				(clearance 0)
			)
			(min_thickness 0.25)
			(keepout
				(tracks allowed)
				(vias not_allowed)
				(pads allowed)
				(copperpour not_allowed)
				(footprints allowed)
			)
			(placement
				(enabled no)
				(sheetname "")
			)
			(fill
				(thermal_gap 0.5)
				(thermal_bridge_width 0.5)
				(island_removal_mode 0)
			)
			(polygon
				(pts
					(xy 369.189 -110.744) (xy 369.189 -111.252) (xy 368.808 -111.252) (xy 368.808 -110.744)
				)
			)
		)
	)
	(footprint ""
		(layer "B.Cu")
		(at 401.25777 -126.389384 90)
		(property "Reference" "C2M24"
			(at 0 0 90)
			(layer "B.SilkS")
			(hide yes)
			(effects
				(font
					(size 1.27 1.27)
				)
				(justify mirror)
			)
		)
		(property "Value" ""
			(at 0 0 90)
			(layer "B.Fab")
			(effects
				(font
					(size 1.27 1.27)
				)
				(justify mirror)
			)
		)
		(duplicate_pad_numbers_are_jumpers no)
		(fp_poly
			(pts
				(xy -0.3048 -0.1016) (xy -0.3048 0.9906) (xy 0.3048 0.9906) (xy 0.3048 -0.1016)
			)
			(stroke
				(width 0)
				(type default)
			)
			(fill no)
			(layer "B.CrtYd")
		)
		(fp_line
			(start 0.3048 -0.1016)
			(end 0.3048 0.9906)
			(stroke
				(width 0.1)
				(type default)
			)
			(layer "B.Fab")
		)
		(fp_line
			(start -0.3048 -0.1016)
			(end 0.3048 -0.1016)
			(stroke
				(width 0.1)
				(type default)
			)
			(layer "B.Fab")
		)
		(fp_line
			(start 0.3048 0.9906)
			(end -0.3048 0.9906)
			(stroke
				(width 0.1)
				(type default)
			)
			(layer "B.Fab")
		)
		(fp_line
			(start -0.3048 0.9906)
			(end -0.3048 -0.1016)
			(stroke
				(width 0.1)
				(type default)
			)
			(layer "B.Fab")
		)
		(pad "1" smd rect
			(at 0 0 270)
			(size 0.508 0.508)
			(layers "B.Cu" "B.Mask" "B.Paste")
			(net "PE_PCH_SPRV_TX_DN")
		)
		(pad "2" smd rect
			(at 0 0.889 270)
			(size 0.508 0.508)
			(layers "B.Cu" "B.Mask" "B.Paste")
			(net "PE_PCH_SPRV_TX_C_DN")
		)
		(zone
			(layer "B.Cu")
			(hatch none 0.5)
			(connect_pads
				(clearance 0)
			)
			(min_thickness 0.25)
			(keepout
				(tracks allowed)
				(vias not_allowed)
				(pads allowed)
				(copperpour not_allowed)
				(footprints allowed)
			)
			(placement
				(enabled no)
				(sheetname "")
			)
			(fill
				(thermal_gap 0.5)
				(thermal_bridge_width 0.5)
				(island_removal_mode 0)
			)
			(polygon
				(pts
					(xy 401.51177 -126.643384) (xy 401.51177 -126.135384) (xy 401.89277 -126.135384) (xy 401.89277 -126.643384)
				)
			)
		)
		(zone
			(layer "B.Cu")
			(hatch none 0.5)
			(connect_pads
				(clearance 0)
			)
			(min_thickness 0.25)
			(keepout
				(tracks not_allowed)
				(vias allowed)
				(pads allowed)
				(copperpour not_allowed)
				(footprints allowed)
			)
			(placement
				(enabled no)
				(sheetname "")
			)
			(fill
				(thermal_gap 0.5)
				(thermal_bridge_width 0.5)
				(island_removal_mode 0)
			)
			(polygon
				(pts
					(xy 401.89277 -126.643384) (xy 401.89277 -126.135384) (xy 401.51177 -126.135384) (xy 401.51177 -126.643384)
				)
			)
		)
	)
	(footprint ""
		(layer "B.Cu")
		(at 418.719 -34.3535)
		(property "Reference" "C25W55"
			(at 0.8382 -0.67818 0)
			(unlocked yes)
			(layer "B.SilkS")
			(effects
				(font
					(size 0.4064 0.254)
					(thickness 0.1524)
				)
				(justify left mirror)
			)
		)
		(property "Value" ""
			(at 0 0 0)
			(layer "B.Fab")
			(effects
				(font
					(size 1.27 1.27)
				)
				(justify mirror)
			)
		)
		(duplicate_pad_numbers_are_jumpers no)
		(fp_poly
			(pts
				(xy -0.3048 -0.1016) (xy -0.3048 0.9906) (xy 0.3048 0.9906) (xy 0.3048 -0.1016)
			)
			(stroke
				(width 0)
				(type default)
			)
			(fill no)
			(layer "B.CrtYd")
		)
		(fp_line
			(start -0.3048 -0.1016)
			(end 0.3048 -0.1016)
			(stroke
				(width 0.1)
				(type default)
			)
			(layer "B.Fab")
		)
		(fp_line
			(start -0.3048 0.9906)
			(end -0.3048 -0.1016)
			(stroke
				(width 0.1)
				(type default)
			)
			(layer "B.Fab")
		)
		(fp_line
			(start 0.3048 -0.1016)
			(end 0.3048 0.9906)
			(stroke
				(width 0.1)
				(type default)
			)
			(layer "B.Fab")
		)
		(fp_line
			(start 0.3048 0.9906)
			(end -0.3048 0.9906)
			(stroke
				(width 0.1)
				(type default)
			)
			(layer "B.Fab")
		)
		(pad "1" smd rect
			(at 0 0 180)
			(size 0.508 0.508)
			(layers "B.Cu" "B.Mask" "B.Paste")
			(net "P1V2_AUX_BMC")
		)
		(pad "2" smd rect
			(at 0 0.889 180)
			(size 0.508 0.508)
			(layers "B.Cu" "B.Mask" "B.Paste")
			(net "GND")
		)
		(zone
			(layer "B.Cu")
			(hatch none 0.5)
			(connect_pads
				(clearance 0)
			)
			(min_thickness 0.25)
			(keepout
				(tracks allowed)
				(vias not_allowed)
				(pads allowed)
				(copperpour not_allowed)
				(footprints allowed)
			)
			(placement
				(enabled no)
				(sheetname "")
			)
			(fill
				(thermal_gap 0.5)
				(thermal_bridge_width 0.5)
				(island_removal_mode 0)
			)
			(polygon
				(pts
					(xy 418.973 -34.0995) (xy 418.465 -34.0995) (xy 418.465 -33.7185) (xy 418.973 -33.7185)
				)
			)
		)
		(zone
			(layer "B.Cu")
			(hatch none 0.5)
			(connect_pads
				(clearance 0)
			)
			(min_thickness 0.25)
			(keepout
				(tracks not_allowed)
				(vias allowed)
				(pads allowed)
				(copperpour not_allowed)
				(footprints allowed)
			)
			(placement
				(enabled no)
				(sheetname "")
			)
			(fill
				(thermal_gap 0.5)
				(thermal_bridge_width 0.5)
				(island_removal_mode 0)
			)
			(polygon
				(pts
					(xy 418.973 -33.7185) (xy 418.465 -33.7185) (xy 418.465 -34.0995) (xy 418.973 -34.0995)
				)
			)
		)
	)
)
